(kicad_pcb
	(version 20260206)
	(generator "pcbnew")
	(generator_version "10.0")
	(general
		(thickness 1.6)
		(legacy_teardrops no)
	)
	(paper "A4")
	(title_block
		(title "04192023_DAF0TMB3IC0_F0TG_MB_C_brd_V02_OCP.brd")
		(comment 1 "Grand Teton / footprints 1038-1043 of 8354")
	)
	(layers
		(0 "F.Cu" signal "TOP")
		(4 "In1.Cu" signal "GND")
		(6 "In2.Cu" signal "IN1")
		(8 "In3.Cu" signal "GND1")
		(10 "In4.Cu" signal "IN2")
		(12 "In5.Cu" signal "GND2")
		(14 "In6.Cu" signal "IN3")
		(16 "In7.Cu" signal "GND3")
		(18 "In8.Cu" signal "VCC")
		(20 "In9.Cu" signal "VCC1")
		(22 "In10.Cu" signal "GND4")
		(24 "In11.Cu" signal "IN4")
		(26 "In12.Cu" signal "GND5")
		(28 "In13.Cu" signal "IN5")
		(30 "In14.Cu" signal "GND6")
		(32 "In15.Cu" signal "IN6")
		(34 "In16.Cu" signal "GND7")
		(2 "B.Cu" signal "BOTTOM")
		(9 "F.Adhes" user "F.Adhesive")
		(11 "B.Adhes" user "B.Adhesive")
		(13 "F.Paste" user "Package Geometry/Pastemask Top")
		(15 "B.Paste" user "Package Geometry/Pastemask Bottom")
		(5 "F.SilkS" user "Ref Des/Silkscreen Top")
		(7 "B.SilkS" user "Ref Des/Silkscreen Bottom")
		(1 "F.Mask" user "Board Geometry/Soldermask Top")
		(3 "B.Mask" user "Board Geometry/Soldermask Bottom")
		(17 "Dwgs.User" user "User.Drawings")
		(19 "Cmts.User" user "User.Comments")
		(21 "Eco1.User" user "User.Eco1")
		(23 "Eco2.User" user "User.Eco2")
		(25 "Edge.Cuts" user "Board Geometry/Outline")
		(27 "Margin" user)
		(31 "F.CrtYd" user "Package Geometry/Place Bound Top")
		(29 "B.CrtYd" user "Package Geometry/Place Bound Bottom")
		(35 "F.Fab" user "Ref Des/Assembly Top")
		(33 "B.Fab" user "Ref Des/Assembly Bottom")
	)
	(footprint ""
		(layer "F.Cu")
		(at 302.241458 -112.827308)
		(property "Reference" "R60"
			(at 0 0 0)
			(layer "F.SilkS")
			(hide yes)
			(effects
				(font
					(size 1.27 1.27)
				)
			)
		)
		(property "Value" ""
			(at 0 0 0)
			(layer "F.Fab")
			(effects
				(font
					(size 1.27 1.27)
				)
			)
		)
		(duplicate_pad_numbers_are_jumpers no)
		(fp_line
			(start -0.7874 -0.4064)
			(end 0.7874 -0.4064)
			(stroke
				(width 0.1524)
				(type default)
			)
			(layer "F.SilkS")
		)
		(fp_line
			(start -0.7874 0.4064)
			(end -0.7874 -0.4064)
			(stroke
				(width 0.1524)
				(type default)
			)
			(layer "F.SilkS")
		)
		(fp_line
			(start 0.7874 -0.4064)
			(end 0.7874 0.4064)
			(stroke
				(width 0.1524)
				(type default)
			)
			(layer "F.SilkS")
		)
		(fp_line
			(start 0.7874 0.4064)
			(end -0.7874 0.4064)
			(stroke
				(width 0.1524)
				(type default)
			)
			(layer "F.SilkS")
		)
		(fp_line
			(start -0.67945 -0.305054)
			(end -0.12065 -0.305054)
			(stroke
				(width 0.1)
				(type default)
			)
			(layer "F.Fab")
		)
		(fp_line
			(start -0.67945 0.3048)
			(end -0.67945 -0.305054)
			(stroke
				(width 0.1)
				(type default)
			)
			(layer "F.Fab")
		)
		(fp_line
			(start -0.12065 -0.305054)
			(end -0.12065 -0.2794)
			(stroke
				(width 0.1)
				(type default)
			)
			(layer "F.Fab")
		)
		(fp_line
			(start -0.12065 -0.2794)
			(end 0.12065 -0.2794)
			(stroke
				(width 0.1)
				(type default)
			)
			(layer "F.Fab")
		)
		(fp_line
			(start -0.12065 0.2794)
			(end -0.12065 0.3048)
			(stroke
				(width 0.1)
				(type default)
			)
			(layer "F.Fab")
		)
		(fp_line
			(start -0.12065 0.3048)
			(end -0.67945 0.3048)
			(stroke
				(width 0.1)
				(type default)
			)
			(layer "F.Fab")
		)
		(fp_line
			(start 0.120396 0.2794)
			(end -0.12065 0.2794)
			(stroke
				(width 0.1)
				(type default)
			)
			(layer "F.Fab")
		)
		(fp_line
			(start 0.120396 0.3048)
			(end 0.120396 0.2794)
			(stroke
				(width 0.1)
				(type default)
			)
			(layer "F.Fab")
		)
		(fp_line
			(start 0.12065 -0.3048)
			(end 0.67945 -0.3048)
			(stroke
				(width 0.1)
				(type default)
			)
			(layer "F.Fab")
		)
		(fp_line
			(start 0.12065 -0.2794)
			(end 0.12065 -0.3048)
			(stroke
				(width 0.1)
				(type default)
			)
			(layer "F.Fab")
		)
		(fp_line
			(start 0.67945 -0.3048)
			(end 0.67945 0.3048)
			(stroke
				(width 0.1)
				(type default)
			)
			(layer "F.Fab")
		)
		(fp_line
			(start 0.67945 0.3048)
			(end 0.120396 0.3048)
			(stroke
				(width 0.1)
				(type default)
			)
			(layer "F.Fab")
		)
		(pad "1" smd circle
			(at -0.40005 0)
			(size 0 0)
			(layers "F.Cu" "F.Mask" "F.Paste")
			(net "P3V3_AUX")
		)
		(pad "2" smd circle
			(at 0.40005 0)
			(size 0 0)
			(layers "F.Cu" "F.Mask" "F.Paste")
			(net "CPU_FRU_ADDR1")
		)
	)
	(footprint ""
		(layer "F.Cu")
		(at 410.869638 -163.684966 90)
		(property "Reference" "PC608_3"
			(at 0 0 90)
			(layer "F.SilkS")
			(hide yes)
			(effects
				(font
					(size 1.27 1.27)
				)
			)
		)
		(property "Value" ""
			(at 0 0 90)
			(layer "F.Fab")
			(effects
				(font
					(size 1.27 1.27)
				)
			)
		)
		(duplicate_pad_numbers_are_jumpers no)
		(fp_line
			(start 0.7874 -0.4064)
			(end 0.7874 0.4064)
			(stroke
				(width 0.1524)
				(type default)
			)
			(layer "F.SilkS")
		)
		(fp_line
			(start -0.7874 -0.4064)
			(end 0.7874 -0.4064)
			(stroke
				(width 0.1524)
				(type default)
			)
			(layer "F.SilkS")
		)
		(fp_line
			(start 0.7874 0.4064)
			(end -0.7874 0.4064)
			(stroke
				(width 0.1524)
				(type default)
			)
			(layer "F.SilkS")
		)
		(fp_line
			(start -0.7874 0.4064)
			(end -0.7874 -0.4064)
			(stroke
				(width 0.1524)
				(type default)
			)
			(layer "F.SilkS")
		)
		(fp_line
			(start -0.12065 -0.305054)
			(end -0.12065 -0.2794)
			(stroke
				(width 0.1)
				(type default)
			)
			(layer "F.Fab")
		)
		(fp_line
			(start -0.67945 -0.305054)
			(end -0.12065 -0.305054)
			(stroke
				(width 0.1)
				(type default)
			)
			(layer "F.Fab")
		)
		(fp_line
			(start 0.67945 -0.3048)
			(end 0.67945 0.3048)
			(stroke
				(width 0.1)
				(type default)
			)
			(layer "F.Fab")
		)
		(fp_line
			(start 0.12065 -0.3048)
			(end 0.67945 -0.3048)
			(stroke
				(width 0.1)
				(type default)
			)
			(layer "F.Fab")
		)
		(fp_line
			(start 0.12065 -0.2794)
			(end 0.12065 -0.3048)
			(stroke
				(width 0.1)
				(type default)
			)
			(layer "F.Fab")
		)
		(fp_line
			(start -0.12065 -0.2794)
			(end 0.12065 -0.2794)
			(stroke
				(width 0.1)
				(type default)
			)
			(layer "F.Fab")
		)
		(fp_line
			(start 0.120396 0.2794)
			(end -0.12065 0.2794)
			(stroke
				(width 0.1)
				(type default)
			)
			(layer "F.Fab")
		)
		(fp_line
			(start -0.12065 0.2794)
			(end -0.12065 0.3048)
			(stroke
				(width 0.1)
				(type default)
			)
			(layer "F.Fab")
		)
		(fp_line
			(start 0.67945 0.3048)
			(end 0.120396 0.3048)
			(stroke
				(width 0.1)
				(type default)
			)
			(layer "F.Fab")
		)
		(fp_line
			(start 0.120396 0.3048)
			(end 0.120396 0.2794)
			(stroke
				(width 0.1)
				(type default)
			)
			(layer "F.Fab")
		)
		(fp_line
			(start -0.12065 0.3048)
			(end -0.67945 0.3048)
			(stroke
				(width 0.1)
				(type default)
			)
			(layer "F.Fab")
		)
		(fp_line
			(start -0.67945 0.3048)
			(end -0.67945 -0.305054)
			(stroke
				(width 0.1)
				(type default)
			)
			(layer "F.Fab")
		)
		(pad "1" smd circle
			(at -0.40005 0 90)
			(size 0 0)
			(layers "F.Cu" "F.Mask" "F.Paste")
			(net "SW_P12V_AUX_PVDDCR_SOC_P0_FLT")
		)
		(pad "2" smd circle
			(at 0.40005 0 90)
			(size 0 0)
			(layers "F.Cu" "F.Mask" "F.Paste")
			(net "GND")
		)
	)
	(footprint ""
		(layer "F.Cu")
		(at 4.410202 -58.863992 -90)
		(property "Reference" "R929"
			(at 0 0 270)
			(layer "F.SilkS")
			(hide yes)
			(effects
				(font
					(size 1.27 1.27)
				)
			)
		)
		(property "Value" ""
			(at 0 0 270)
			(layer "F.Fab")
			(effects
				(font
					(size 1.27 1.27)
				)
			)
		)
		(duplicate_pad_numbers_are_jumpers no)
		(fp_line
			(start -0.7874 0.4064)
			(end -0.7874 -0.4064)
			(stroke
				(width 0.1524)
				(type default)
			)
			(layer "F.SilkS")
		)
		(fp_line
			(start 0.7874 0.4064)
			(end -0.7874 0.4064)
			(stroke
				(width 0.1524)
				(type default)
			)
			(layer "F.SilkS")
		)
		(fp_line
			(start -0.7874 -0.4064)
			(end 0.7874 -0.4064)
			(stroke
				(width 0.1524)
				(type default)
			)
			(layer "F.SilkS")
		)
		(fp_line
			(start 0.7874 -0.4064)
			(end 0.7874 0.4064)
			(stroke
				(width 0.1524)
				(type default)
			)
			(layer "F.SilkS")
		)
		(fp_line
			(start -0.67945 0.3048)
			(end -0.67945 -0.305054)
			(stroke
				(width 0.1)
				(type default)
			)
			(layer "F.Fab")
		)
		(fp_line
			(start -0.12065 0.3048)
			(end -0.67945 0.3048)
			(stroke
				(width 0.1)
				(type default)
			)
			(layer "F.Fab")
		)
		(fp_line
			(start 0.120396 0.3048)
			(end 0.120396 0.2794)
			(stroke
				(width 0.1)
				(type default)
			)
			(layer "F.Fab")
		)
		(fp_line
			(start 0.67945 0.3048)
			(end 0.120396 0.3048)
			(stroke
				(width 0.1)
				(type default)
			)
			(layer "F.Fab")
		)
		(fp_line
			(start -0.12065 0.2794)
			(end -0.12065 0.3048)
			(stroke
				(width 0.1)
				(type default)
			)
			(layer "F.Fab")
		)
		(fp_line
			(start 0.120396 0.2794)
			(end -0.12065 0.2794)
			(stroke
				(width 0.1)
				(type default)
			)
			(layer "F.Fab")
		)
		(fp_line
			(start -0.12065 -0.2794)
			(end 0.12065 -0.2794)
			(stroke
				(width 0.1)
				(type default)
			)
			(layer "F.Fab")
		)
		(fp_line
			(start 0.12065 -0.2794)
			(end 0.12065 -0.3048)
			(stroke
				(width 0.1)
				(type default)
			)
			(layer "F.Fab")
		)
		(fp_line
			(start 0.12065 -0.3048)
			(end 0.67945 -0.3048)
			(stroke
				(width 0.1)
				(type default)
			)
			(layer "F.Fab")
		)
		(fp_line
			(start 0.67945 -0.3048)
			(end 0.67945 0.3048)
			(stroke
				(width 0.1)
				(type default)
			)
			(layer "F.Fab")
		)
		(fp_line
			(start -0.67945 -0.305054)
			(end -0.12065 -0.305054)
			(stroke
				(width 0.1)
				(type default)
			)
			(layer "F.Fab")
		)
		(fp_line
			(start -0.12065 -0.305054)
			(end -0.12065 -0.2794)
			(stroke
				(width 0.1)
				(type default)
			)
			(layer "F.Fab")
		)
		(pad "1" smd circle
			(at -0.40005 0 270)
			(size 0 0)
			(layers "F.Cu" "F.Mask" "F.Paste")
			(net "CPU1_XTRIG_L4")
		)
		(pad "2" smd circle
			(at 0.40005 0 270)
			(size 0 0)
			(layers "F.Cu" "F.Mask" "F.Paste")
			(net "CPU1_XTRIG_R1_L4")
		)
	)
	(footprint ""
		(layer "F.Cu")
		(at 53.08473 -17.623536 90)
		(property "Reference" "C705"
			(at 0 0 90)
			(layer "F.SilkS")
			(hide yes)
			(effects
				(font
					(size 1.27 1.27)
				)
			)
		)
		(property "Value" ""
			(at 0 0 90)
			(layer "F.Fab")
			(effects
				(font
					(size 1.27 1.27)
				)
			)
		)
		(duplicate_pad_numbers_are_jumpers no)
		(fp_line
			(start 0.299974 -0.150114)
			(end 0.299974 0.150114)
			(stroke
				(width 0.1)
				(type default)
			)
			(layer "F.Fab")
		)
		(fp_line
			(start -0.299974 -0.150114)
			(end 0.299974 -0.150114)
			(stroke
				(width 0.1)
				(type default)
			)
			(layer "F.Fab")
		)
		(fp_line
			(start 0.299974 0.150114)
			(end -0.299974 0.150114)
			(stroke
				(width 0.1)
				(type default)
			)
			(layer "F.Fab")
		)
		(fp_line
			(start -0.299974 0.150114)
			(end -0.299974 -0.150114)
			(stroke
				(width 0.1)
				(type default)
			)
			(layer "F.Fab")
		)
		(pad "1" smd rect
			(at -0.2667 0 90)
			(size 0.3048 0.381)
			(layers "F.Cu" "F.Mask" "F.Paste")
			(net "P5E_CPU1_G1_TX_C_DP<2>")
		)
		(pad "2" smd rect
			(at 0.2667 0 90)
			(size 0.3048 0.381)
			(layers "F.Cu" "F.Mask" "F.Paste")
			(net "P5E_CPU1_G1_TX_DP<2>")
		)
	)
	(footprint ""
		(layer "F.Cu")
		(at 227.430076 -294.978074 90)
		(property "Reference" "PC6526"
			(at 0 0 90)
			(layer "F.SilkS")
			(hide yes)
			(effects
				(font
					(size 1.27 1.27)
				)
			)
		)
		(property "Value" ""
			(at 0 0 90)
			(layer "F.Fab")
			(effects
				(font
					(size 1.27 1.27)
				)
			)
		)
		(duplicate_pad_numbers_are_jumpers no)
		(fp_line
			(start 0.7874 -0.4064)
			(end 0.7874 0.4064)
			(stroke
				(width 0.1524)
				(type default)
			)
			(layer "F.SilkS")
		)
		(fp_line
			(start -0.7874 -0.4064)
			(end 0.7874 -0.4064)
			(stroke
				(width 0.1524)
				(type default)
			)
			(layer "F.SilkS")
		)
		(fp_line
			(start 0.7874 0.4064)
			(end -0.7874 0.4064)
			(stroke
				(width 0.1524)
				(type default)
			)
			(layer "F.SilkS")
		)
		(fp_line
			(start -0.7874 0.4064)
			(end -0.7874 -0.4064)
			(stroke
				(width 0.1524)
				(type default)
			)
			(layer "F.SilkS")
		)
		(fp_line
			(start -0.12065 -0.305054)
			(end -0.12065 -0.2794)
			(stroke
				(width 0.1)
				(type default)
			)
			(layer "F.Fab")
		)
		(fp_line
			(start -0.67945 -0.305054)
			(end -0.12065 -0.305054)
			(stroke
				(width 0.1)
				(type default)
			)
			(layer "F.Fab")
		)
		(fp_line
			(start 0.67945 -0.3048)
			(end 0.67945 0.3048)
			(stroke
				(width 0.1)
				(type default)
			)
			(layer "F.Fab")
		)
		(fp_line
			(start 0.12065 -0.3048)
			(end 0.67945 -0.3048)
			(stroke
				(width 0.1)
				(type default)
			)
			(layer "F.Fab")
		)
		(fp_line
			(start 0.12065 -0.2794)
			(end 0.12065 -0.3048)
			(stroke
				(width 0.1)
				(type default)
			)
			(layer "F.Fab")
		)
		(fp_line
			(start -0.12065 -0.2794)
			(end 0.12065 -0.2794)
			(stroke
				(width 0.1)
				(type default)
			)
			(layer "F.Fab")
		)
		(fp_line
			(start 0.120396 0.2794)
			(end -0.12065 0.2794)
			(stroke
				(width 0.1)
				(type default)
			)
			(layer "F.Fab")
		)
		(fp_line
			(start -0.12065 0.2794)
			(end -0.12065 0.3048)
			(stroke
				(width 0.1)
				(type default)
			)
			(layer "F.Fab")
		)
		(fp_line
			(start 0.67945 0.3048)
			(end 0.120396 0.3048)
			(stroke
				(width 0.1)
				(type default)
			)
			(layer "F.Fab")
		)
		(fp_line
			(start 0.120396 0.3048)
			(end 0.120396 0.2794)
			(stroke
				(width 0.1)
				(type default)
			)
			(layer "F.Fab")
		)
		(fp_line
			(start -0.12065 0.3048)
			(end -0.67945 0.3048)
			(stroke
				(width 0.1)
				(type default)
			)
			(layer "F.Fab")
		)
		(fp_line
			(start -0.67945 0.3048)
			(end -0.67945 -0.305054)
			(stroke
				(width 0.1)
				(type default)
			)
			(layer "F.Fab")
		)
		(pad "1" smd circle
			(at -0.40005 0 90)
			(size 0 0)
			(layers "F.Cu" "F.Mask" "F.Paste")
			(net "SW_P1V8_RETIMER_CPU1_BST_R")
		)
		(pad "2" smd circle
			(at 0.40005 0 90)
			(size 0 0)
			(layers "F.Cu" "F.Mask" "F.Paste")
			(net "SW_P1V8_RETIMER_CPU1_SW")
		)
	)
	(footprint ""
		(layer "F.Cu")
		(at 107.256834 -136.306052 90)
		(property "Reference" "PQ11"
			(at -1.27 2.31267 90)
			(unlocked yes)
			(layer "F.SilkS")
			(effects
				(font
					(size 0.7874 0.5842)
					(thickness 0.1524)
				)
				(justify left)
			)
		)
		(property "Value" ""
			(at 0 0 90)
			(layer "F.Fab")
			(effects
				(font
					(size 1.27 1.27)
				)
			)
		)
		(duplicate_pad_numbers_are_jumpers no)
		(fp_line
			(start 1.603248 -1.500124)
			(end 1.603248 1.500124)
			(stroke
				(width 0.1524)
				(type default)
			)
			(layer "F.SilkS")
		)
		(fp_line
			(start -1.603248 -1.500124)
			(end 1.603248 -1.500124)
			(stroke
				(width 0.1524)
				(type default)
			)
			(layer "F.SilkS")
		)
		(fp_line
			(start 1.603248 1.500124)
			(end -1.603248 1.500124)
			(stroke
				(width 0.1524)
				(type default)
			)
			(layer "F.SilkS")
		)
		(fp_line
			(start -1.603248 1.500124)
			(end -1.603248 -1.500124)
			(stroke
				(width 0.1524)
				(type default)
			)
			(layer "F.SilkS")
		)
		(fp_line
			(start 0.700024 -1.500124)
			(end -0.700024 -1.500124)
			(stroke
				(width 0.1)
				(type default)
			)
			(layer "F.Fab")
		)
		(fp_line
			(start -0.700024 -1.500124)
			(end -0.700024 -1.169924)
			(stroke
				(width 0.1)
				(type default)
			)
			(layer "F.Fab")
		)
		(fp_line
			(start -0.700024 -1.169924)
			(end -1.249934 -1.169924)
			(stroke
				(width 0.1)
				(type default)
			)
			(layer "F.Fab")
		)
		(fp_line
			(start -1.249934 -1.169924)
			(end -1.249934 -0.729996)
			(stroke
				(width 0.1)
				(type default)
			)
			(layer "F.Fab")
		)
		(fp_line
			(start -0.6985 -0.729996)
			(end -0.6985 0.729996)
			(stroke
				(width 0.1)
				(type default)
			)
			(layer "F.Fab")
		)
		(fp_line
			(start -1.249934 -0.729996)
			(end -0.6985 -0.729996)
			(stroke
				(width 0.1)
				(type default)
			)
			(layer "F.Fab")
		)
		(fp_line
			(start 1.249934 -0.219964)
			(end 0.700024 -0.219964)
			(stroke
				(width 0.1)
				(type default)
			)
			(layer "F.Fab")
		)
		(fp_line
			(start 0.700024 -0.219964)
			(end 0.700024 -1.500124)
			(stroke
				(width 0.1)
				(type default)
			)
			(layer "F.Fab")
		)
		(fp_line
			(start 1.249934 0.219964)
			(end 1.249934 -0.219964)
			(stroke
				(width 0.1)
				(type default)
			)
			(layer "F.Fab")
		)
		(fp_line
			(start 0.700024 0.219964)
			(end 1.249934 0.219964)
			(stroke
				(width 0.1)
				(type default)
			)
			(layer "F.Fab")
		)
		(fp_line
			(start -0.6985 0.729996)
			(end -1.249934 0.729996)
			(stroke
				(width 0.1)
				(type default)
			)
			(layer "F.Fab")
		)
		(fp_line
			(start -1.249934 0.729996)
			(end -1.249934 1.169924)
			(stroke
				(width 0.1)
				(type default)
			)
			(layer "F.Fab")
		)
		(fp_line
			(start -0.700024 1.169924)
			(end -0.700024 1.500124)
			(stroke
				(width 0.1)
				(type default)
			)
			(layer "F.Fab")
		)
		(fp_line
			(start -1.249934 1.169924)
			(end -0.700024 1.169924)
			(stroke
				(width 0.1)
				(type default)
			)
			(layer "F.Fab")
		)
		(fp_line
			(start 0.700024 1.500124)
			(end 0.700024 0.219964)
			(stroke
				(width 0.1)
				(type default)
			)
			(layer "F.Fab")
		)
		(fp_line
			(start -0.700024 1.500124)
			(end 0.700024 1.500124)
			(stroke
				(width 0.1)
				(type default)
			)
			(layer "F.Fab")
		)
		(fp_rect
			(start -0.700024 1.500124)
			(end 0.700024 -1.500124)
			(stroke
				(width 0)
				(type default)
			)
			(fill no)
			(layer "F.Fab")
		)
		(pad "D" smd rect
			(at 0.999998 0)
			(size 0.8128 0.9144)
			(layers "F.Cu" "F.Mask" "F.Paste")
			(net "PVDDCR_SOC_P1_EN//ADDR_CFG")
		)
		(pad "G" smd rect
			(at -0.999998 -0.94996)
			(size 0.8128 0.9144)
			(layers "F.Cu" "F.Mask" "F.Paste")
			(net "PVDDCR_SOC_P1_EN_GD")
		)
		(pad "S" smd rect
			(at -0.999998 0.94996)
			(size 0.8128 0.9144)
			(layers "F.Cu" "F.Mask" "F.Paste")
			(net "P3V3_AUX")
		)
	)
)
